(kicad_pcb
	(version 20260206)
	(generator "pcbnew")
	(generator_version "10.0")
	(general
		(thickness 1.6)
		(legacy_teardrops no)
	)
	(paper "A4")
	(title_block
		(title "dpb — 14545-sa.0730WZS0815.brd")
		(comment 1 "Honey Badger (Wiwynn) / footprints 371-377 of 1066")
	)
	(layers
		(0 "F.Cu" signal "TOP")
		(4 "In1.Cu" signal "L2GND")
		(6 "In2.Cu" signal "L3")
		(8 "In3.Cu" signal "L4VCC")
		(10 "In4.Cu" signal "L5VCC")
		(12 "In5.Cu" signal "L6")
		(14 "In6.Cu" signal "L7GND")
		(2 "B.Cu" signal "BOTTOM")
		(9 "F.Adhes" user "F.Adhesive")
		(11 "B.Adhes" user "B.Adhesive")
		(13 "F.Paste" user "Package Geometry/Pastemask Top")
		(15 "B.Paste" user "Package Geometry/Pastemask Bottom")
		(5 "F.SilkS" user "Ref Des/Silkscreen Top")
		(7 "B.SilkS" user "Ref Des/Silkscreen Bottom")
		(1 "F.Mask" user "Board Geometry/Soldermask Top")
		(3 "B.Mask" user "Board Geometry/Soldermask Bottom")
		(17 "Dwgs.User" user "User.Drawings")
		(19 "Cmts.User" user "User.Comments")
		(21 "Eco1.User" user "User.Eco1")
		(23 "Eco2.User" user "User.Eco2")
		(25 "Edge.Cuts" user "Board Geometry/Outline")
		(27 "Margin" user)
		(31 "F.CrtYd" user "Package Geometry/Place Bound Top")
		(29 "B.CrtYd" user "Package Geometry/Place Bound Bottom")
		(35 "F.Fab" user "Ref Des/Assembly Top")
		(33 "B.Fab" user "Ref Des/Assembly Bottom")
	)
	(footprint ""
		(layer "F.Cu")
		(at 217.762582 -269.466568 -90)
		(property "Reference" "C136"
			(at 0 0 270)
			(layer "F.SilkS")
			(hide yes)
			(effects
				(font
					(size 1.27 1.27)
				)
			)
		)
		(property "Value" "SCD01U50V2KX-1GP"
			(at 1.1811 -2.7051 270)
			(unlocked yes)
			(layer "F.Fab")
			(hide yes)
			(effects
				(font
					(size 1.016 1.016)
					(thickness 0.1524)
				)
			)
		)
		(property "Device Type" "C402H22"
			(at 1.1811 -4.2291 270)
			(unlocked yes)
			(layer "F.Fab")
			(hide yes)
			(effects
				(font
					(size 1.016 1.016)
					(thickness 0.1524)
				)
			)
		)
		(duplicate_pad_numbers_are_jumpers no)
		(fp_rect
			(start -0.4318 0.9525)
			(end 0.4318 -0.9525)
			(stroke
				(width 0)
				(type default)
			)
			(fill no)
			(layer "F.CrtYd")
		)
		(fp_rect
			(start -0.4318 0.9525)
			(end 0.4318 -0.9525)
			(stroke
				(width 0)
				(type default)
			)
			(fill no)
			(layer "F.Fab")
		)
		(pad "1" smd custom
			(at 0 -0.4445 270)
			(size 0.1524 0.1524)
			(layers "F.Cu" "F.Mask" "F.Paste")
			(net "SAS2X28_DRIVE_RX_N_B2")
			(options
				(clearance outline)
				(anchor circle)
			)
			(primitives
				(gr_poly
					(pts
						(arc
							(start 0.3048 -0.2032)
							(mid 0.275042 -0.275042)
							(end 0.2032 -0.3048)
						)
						(arc
							(start -0.2032 -0.3048)
							(mid -0.275042 -0.275042)
							(end -0.3048 -0.2032)
						)
						(arc
							(start -0.3048 0.2032)
							(mid -0.275042 0.275042)
							(end -0.2032 0.3048)
						)
						(arc
							(start 0.2032 0.3048)
							(mid 0.275042 0.275042)
							(end 0.3048 0.2032)
						)
					)
					(width 0)
					(fill yes)
				)
			)
		)
		(pad "2" smd custom
			(at 0 0.4445 270)
			(size 0.1524 0.1524)
			(layers "F.Cu" "F.Mask" "F.Paste")
			(net "SAS2X28_B_HDD2_RX_-")
			(options
				(clearance outline)
				(anchor circle)
			)
			(primitives
				(gr_poly
					(pts
						(arc
							(start 0.3048 -0.2032)
							(mid 0.275042 -0.275042)
							(end 0.2032 -0.3048)
						)
						(arc
							(start -0.2032 -0.3048)
							(mid -0.275042 -0.275042)
							(end -0.3048 -0.2032)
						)
						(arc
							(start -0.3048 0.2032)
							(mid -0.275042 0.275042)
							(end -0.2032 0.3048)
						)
						(arc
							(start 0.2032 0.3048)
							(mid 0.275042 0.275042)
							(end 0.3048 0.2032)
						)
					)
					(width 0)
					(fill yes)
				)
			)
		)
	)
	(footprint ""
		(layer "F.Cu")
		(at 37.210746 -124.996702)
		(property "Reference" "C317"
			(at 0 0 0)
			(layer "F.SilkS")
			(hide yes)
			(effects
				(font
					(size 1.27 1.27)
				)
			)
		)
		(property "Value" "SC10U16V6KX-2GP"
			(at -0.0762 -5.1308 0)
			(unlocked yes)
			(layer "F.Fab")
			(hide yes)
			(effects
				(font
					(size 1.016 1.016)
					(thickness 0.1524)
				)
			)
		)
		(property "Device Type" "C1206H71"
			(at -0.127 -6.6548 0)
			(unlocked yes)
			(layer "F.Fab")
			(hide yes)
			(effects
				(font
					(size 1.016 1.016)
					(thickness 0.1524)
				)
			)
		)
		(duplicate_pad_numbers_are_jumpers no)
		(fp_line
			(start -1.016 -2.2352)
			(end 1.016 -2.2352)
			(stroke
				(width 0.1524)
				(type default)
			)
			(layer "F.SilkS")
		)
		(fp_line
			(start -1.016 -0.8382)
			(end -1.016 -2.2352)
			(stroke
				(width 0.1524)
				(type default)
			)
			(layer "F.SilkS")
		)
		(fp_line
			(start -1.016 2.2352)
			(end -1.016 0.8382)
			(stroke
				(width 0.1524)
				(type default)
			)
			(layer "F.SilkS")
		)
		(fp_line
			(start 1.016 -2.2352)
			(end 1.016 -0.8382)
			(stroke
				(width 0.1524)
				(type default)
			)
			(layer "F.SilkS")
		)
		(fp_line
			(start 1.016 0.8382)
			(end 1.016 2.2352)
			(stroke
				(width 0.1524)
				(type default)
			)
			(layer "F.SilkS")
		)
		(fp_line
			(start 1.016 2.2352)
			(end -1.016 2.2352)
			(stroke
				(width 0.1524)
				(type default)
			)
			(layer "F.SilkS")
		)
		(fp_rect
			(start -1.0922 2.3114)
			(end 1.0922 -2.3114)
			(stroke
				(width 0)
				(type default)
			)
			(fill no)
			(layer "F.CrtYd")
		)
		(fp_poly
			(pts
				(xy 1.0922 -2.3114) (xy 1.0922 2.3114) (xy -1.0922 2.3114) (xy -1.0922 -2.3114)
			)
			(stroke
				(width 0)
				(type default)
			)
			(fill no)
			(layer "F.Fab")
		)
		(pad "1" smd rect
			(at 0 -1.397)
			(size 1.651 1.27)
			(layers "F.Cu" "F.Mask" "F.Paste")
			(net "P5V_HDD13")
		)
		(pad "2" smd rect
			(at 0 1.397)
			(size 1.651 1.27)
			(layers "F.Cu" "F.Mask" "F.Paste")
			(net "GND")
		)
	)
	(footprint ""
		(layer "F.Cu")
		(at 39.750746 -247.7897 90)
		(property "Reference" "R199"
			(at 0 0 90)
			(layer "F.SilkS")
			(hide yes)
			(effects
				(font
					(size 1.27 1.27)
				)
			)
		)
		(property "Value" "402R2F-GP"
			(at 0.064008 -3.993896 90)
			(unlocked yes)
			(layer "F.Fab")
			(hide yes)
			(effects
				(font
					(size 1.016 1.016)
					(thickness 0.1524)
				)
			)
		)
		(property "Device Type" "R402H16"
			(at 0.064008 -5.517896 90)
			(unlocked yes)
			(layer "F.Fab")
			(hide yes)
			(effects
				(font
					(size 1.016 1.016)
					(thickness 0.1524)
				)
			)
		)
		(duplicate_pad_numbers_are_jumpers no)
		(fp_line
			(start 0.508 -0.9398)
			(end -0.508 -0.9398)
			(stroke
				(width 0.1524)
				(type default)
			)
			(layer "F.SilkS")
		)
		(fp_line
			(start -0.508 -0.9398)
			(end -0.508 0.9398)
			(stroke
				(width 0.1524)
				(type default)
			)
			(layer "F.SilkS")
		)
		(fp_rect
			(start -0.508 0.9398)
			(end 0.508 -0.9398)
			(stroke
				(width 0)
				(type default)
			)
			(fill no)
			(layer "F.CrtYd")
		)
		(fp_rect
			(start -0.508 0.9398)
			(end 0.508 -0.9398)
			(stroke
				(width 0)
				(type default)
			)
			(fill no)
			(layer "F.Fab")
		)
		(pad "1" smd custom
			(at 0 -0.4445 90)
			(size 0.1397 0.1397)
			(layers "F.Cu" "F.Mask" "F.Paste")
			(net "P5VB_HDD7_LED")
			(options
				(clearance outline)
				(anchor circle)
			)
			(primitives
				(gr_poly
					(pts
						(arc
							(start -0.1778 -0.2794)
							(mid -0.249642 -0.249642)
							(end -0.2794 -0.1778)
						)
						(arc
							(start -0.2794 0.1778)
							(mid -0.249642 0.249642)
							(end -0.1778 0.2794)
						)
						(arc
							(start 0.1778 0.2794)
							(mid 0.249642 0.249642)
							(end 0.2794 0.1778)
						)
						(arc
							(start 0.2794 -0.1778)
							(mid 0.249642 -0.249642)
							(end 0.1778 -0.2794)
						)
					)
					(width 0)
					(fill yes)
				)
			)
		)
		(pad "2" smd custom
			(at 0 0.4445 90)
			(size 0.1397 0.1397)
			(layers "F.Cu" "F.Mask" "F.Paste")
			(net "DRV_ACT_7")
			(options
				(clearance outline)
				(anchor circle)
			)
			(primitives
				(gr_poly
					(pts
						(arc
							(start -0.1778 -0.2794)
							(mid -0.249642 -0.249642)
							(end -0.2794 -0.1778)
						)
						(arc
							(start -0.2794 0.1778)
							(mid -0.249642 0.249642)
							(end -0.1778 0.2794)
						)
						(arc
							(start 0.1778 0.2794)
							(mid 0.249642 0.249642)
							(end 0.2794 0.1778)
						)
						(arc
							(start 0.2794 -0.1778)
							(mid 0.249642 -0.249642)
							(end 0.1778 -0.2794)
						)
					)
					(width 0)
					(fill yes)
				)
			)
		)
	)
	(footprint ""
		(layer "F.Cu")
		(at 193.04 -191.77 90)
		(property "Reference" "R552"
			(at 0 0 90)
			(layer "F.SilkS")
			(hide yes)
			(effects
				(font
					(size 1.27 1.27)
				)
			)
		)
		(property "Value" "200KR2F-L-GP"
			(at 0.064008 -3.993896 90)
			(unlocked yes)
			(layer "F.Fab")
			(hide yes)
			(effects
				(font
					(size 1.016 1.016)
					(thickness 0.1524)
				)
			)
		)
		(property "Device Type" "R402H16"
			(at 0.064008 -5.517896 90)
			(unlocked yes)
			(layer "F.Fab")
			(hide yes)
			(effects
				(font
					(size 1.016 1.016)
					(thickness 0.1524)
				)
			)
		)
		(duplicate_pad_numbers_are_jumpers no)
		(fp_line
			(start 0.508 -0.9398)
			(end -0.508 -0.9398)
			(stroke
				(width 0.1524)
				(type default)
			)
			(layer "F.SilkS")
		)
		(fp_line
			(start -0.508 -0.9398)
			(end -0.508 0.9398)
			(stroke
				(width 0.1524)
				(type default)
			)
			(layer "F.SilkS")
		)
		(fp_rect
			(start -0.508 0.9398)
			(end 0.508 -0.9398)
			(stroke
				(width 0)
				(type default)
			)
			(fill no)
			(layer "F.CrtYd")
		)
		(fp_rect
			(start -0.508 0.9398)
			(end 0.508 -0.9398)
			(stroke
				(width 0)
				(type default)
			)
			(fill no)
			(layer "F.Fab")
		)
		(pad "1" smd custom
			(at 0 -0.4445 90)
			(size 0.1397 0.1397)
			(layers "F.Cu" "F.Mask" "F.Paste")
			(net "SW_HDD3_R")
			(options
				(clearance outline)
				(anchor circle)
			)
			(primitives
				(gr_poly
					(pts
						(arc
							(start -0.1778 -0.2794)
							(mid -0.249642 -0.249642)
							(end -0.2794 -0.1778)
						)
						(arc
							(start -0.2794 0.1778)
							(mid -0.249642 0.249642)
							(end -0.1778 0.2794)
						)
						(arc
							(start 0.1778 0.2794)
							(mid 0.249642 0.249642)
							(end 0.2794 0.1778)
						)
						(arc
							(start 0.2794 -0.1778)
							(mid 0.249642 -0.249642)
							(end 0.1778 -0.2794)
						)
					)
					(width 0)
					(fill yes)
				)
			)
		)
		(pad "2" smd custom
			(at 0 0.4445 90)
			(size 0.1397 0.1397)
			(layers "F.Cu" "F.Mask" "F.Paste")
			(net "SW_HDD3_N")
			(options
				(clearance outline)
				(anchor circle)
			)
			(primitives
				(gr_poly
					(pts
						(arc
							(start -0.1778 -0.2794)
							(mid -0.249642 -0.249642)
							(end -0.2794 -0.1778)
						)
						(arc
							(start -0.2794 0.1778)
							(mid -0.249642 0.249642)
							(end -0.1778 0.2794)
						)
						(arc
							(start 0.1778 0.2794)
							(mid 0.249642 0.249642)
							(end 0.2794 0.1778)
						)
						(arc
							(start 0.2794 -0.1778)
							(mid 0.249642 -0.249642)
							(end 0.1778 -0.2794)
						)
					)
					(width 0)
					(fill yes)
				)
			)
		)
	)
	(footprint ""
		(layer "F.Cu")
		(at 79.756 -197.866 -90)
		(property "Reference" "R557"
			(at 0 0 270)
			(layer "F.SilkS")
			(hide yes)
			(effects
				(font
					(size 1.27 1.27)
				)
			)
		)
		(property "Value" "200KR2F-L-GP"
			(at 0.064008 -3.993896 270)
			(unlocked yes)
			(layer "F.Fab")
			(hide yes)
			(effects
				(font
					(size 1.016 1.016)
					(thickness 0.1524)
				)
			)
		)
		(property "Device Type" "R402H16"
			(at 0.064008 -5.517896 270)
			(unlocked yes)
			(layer "F.Fab")
			(hide yes)
			(effects
				(font
					(size 1.016 1.016)
					(thickness 0.1524)
				)
			)
		)
		(duplicate_pad_numbers_are_jumpers no)
		(fp_line
			(start -0.508 -0.9398)
			(end -0.508 0.9398)
			(stroke
				(width 0.1524)
				(type default)
			)
			(layer "F.SilkS")
		)
		(fp_line
			(start 0.508 -0.9398)
			(end -0.508 -0.9398)
			(stroke
				(width 0.1524)
				(type default)
			)
			(layer "F.SilkS")
		)
		(fp_rect
			(start -0.508 0.9398)
			(end 0.508 -0.9398)
			(stroke
				(width 0)
				(type default)
			)
			(fill no)
			(layer "F.CrtYd")
		)
		(fp_rect
			(start -0.508 0.9398)
			(end 0.508 -0.9398)
			(stroke
				(width 0)
				(type default)
			)
			(fill no)
			(layer "F.Fab")
		)
		(pad "1" smd custom
			(at 0 -0.4445 270)
			(size 0.1397 0.1397)
			(layers "F.Cu" "F.Mask" "F.Paste")
			(net "SW_HDD8_R")
			(options
				(clearance outline)
				(anchor circle)
			)
			(primitives
				(gr_poly
					(pts
						(arc
							(start -0.1778 -0.2794)
							(mid -0.249642 -0.249642)
							(end -0.2794 -0.1778)
						)
						(arc
							(start -0.2794 0.1778)
							(mid -0.249642 0.249642)
							(end -0.1778 0.2794)
						)
						(arc
							(start 0.1778 0.2794)
							(mid 0.249642 0.249642)
							(end 0.2794 0.1778)
						)
						(arc
							(start 0.2794 -0.1778)
							(mid 0.249642 -0.249642)
							(end 0.1778 -0.2794)
						)
					)
					(width 0)
					(fill yes)
				)
			)
		)
		(pad "2" smd custom
			(at 0 0.4445 270)
			(size 0.1397 0.1397)
			(layers "F.Cu" "F.Mask" "F.Paste")
			(net "SW_HDD8_N")
			(options
				(clearance outline)
				(anchor circle)
			)
			(primitives
				(gr_poly
					(pts
						(arc
							(start -0.1778 -0.2794)
							(mid -0.249642 -0.249642)
							(end -0.2794 -0.1778)
						)
						(arc
							(start -0.2794 0.1778)
							(mid -0.249642 0.249642)
							(end -0.1778 0.2794)
						)
						(arc
							(start 0.1778 0.2794)
							(mid 0.249642 0.249642)
							(end 0.2794 0.1778)
						)
						(arc
							(start 0.2794 -0.1778)
							(mid 0.249642 -0.249642)
							(end 0.1778 -0.2794)
						)
					)
					(width 0)
					(fill yes)
				)
			)
		)
	)
	(footprint ""
		(layer "F.Cu")
		(at 25.9334 -416.941)
		(property "Reference" "C272"
			(at 0 0 0)
			(layer "F.SilkS")
			(hide yes)
			(effects
				(font
					(size 1.27 1.27)
				)
			)
		)
		(property "Value" "SC1U25V3KX-1-GP"
			(at 0 -2.8194 0)
			(unlocked yes)
			(layer "F.Fab")
			(hide yes)
			(effects
				(font
					(size 1.016 1.016)
					(thickness 0.1524)
				)
			)
		)
		(property "Device Type" "C603H36"
			(at 0 -4.3434 0)
			(unlocked yes)
			(layer "F.Fab")
			(hide yes)
			(effects
				(font
					(size 1.016 1.016)
					(thickness 0.1524)
				)
			)
		)
		(duplicate_pad_numbers_are_jumpers no)
		(fp_line
			(start 0.508 0)
			(end -0.508 0)
			(stroke
				(width 0.2032)
				(type default)
			)
			(layer "F.SilkS")
		)
		(fp_rect
			(start -0.5842 1.3335)
			(end 0.5842 -1.3335)
			(stroke
				(width 0)
				(type default)
			)
			(fill no)
			(layer "F.CrtYd")
		)
		(fp_rect
			(start -0.5842 1.3335)
			(end 0.5842 -1.3335)
			(stroke
				(width 0)
				(type default)
			)
			(fill no)
			(layer "F.Fab")
		)
		(pad "1" smd custom
			(at 0 -0.762)
			(size 0.2159 0.2159)
			(layers "F.Cu" "F.Mask" "F.Paste")
			(net "P12V_HDD10")
			(options
				(clearance outline)
				(anchor circle)
			)
			(primitives
				(gr_poly
					(pts
						(arc
							(start -0.3302 -0.4318)
							(mid -0.402042 -0.402042)
							(end -0.4318 -0.3302)
						)
						(arc
							(start -0.4318 0.3302)
							(mid -0.402042 0.402042)
							(end -0.3302 0.4318)
						)
						(arc
							(start 0.3302 0.4318)
							(mid 0.402042 0.402042)
							(end 0.4318 0.3302)
						)
						(arc
							(start 0.4318 -0.3302)
							(mid 0.402042 -0.402042)
							(end 0.3302 -0.4318)
						)
					)
					(width 0)
					(fill yes)
				)
			)
		)
		(pad "2" smd custom
			(at 0 0.762)
			(size 0.2159 0.2159)
			(layers "F.Cu" "F.Mask" "F.Paste")
			(net "GND")
			(options
				(clearance outline)
				(anchor circle)
			)
			(primitives
				(gr_poly
					(pts
						(arc
							(start -0.3302 -0.4318)
							(mid -0.402042 -0.402042)
							(end -0.4318 -0.3302)
						)
						(arc
							(start -0.4318 0.3302)
							(mid -0.402042 0.402042)
							(end -0.3302 0.4318)
						)
						(arc
							(start 0.3302 0.4318)
							(mid 0.402042 0.402042)
							(end 0.4318 0.3302)
						)
						(arc
							(start 0.4318 -0.3302)
							(mid 0.402042 -0.402042)
							(end 0.3302 -0.4318)
						)
					)
					(width 0)
					(fill yes)
				)
			)
		)
	)
	(footprint ""
		(layer "F.Cu")
		(at 9.4234 -154.260804 90)
		(property "Reference" "R549"
			(at 0 0 90)
			(layer "F.SilkS")
			(hide yes)
			(effects
				(font
					(size 1.27 1.27)
				)
			)
		)
		(property "Value" "0R2J-2-GP"
			(at 0.064008 -3.993896 90)
			(unlocked yes)
			(layer "F.Fab")
			(hide yes)
			(effects
				(font
					(size 1.016 1.016)
					(thickness 0.1524)
				)
			)
		)
		(property "Device Type" "R402H16"
			(at 0.064008 -5.517896 90)
			(unlocked yes)
			(layer "F.Fab")
			(hide yes)
			(effects
				(font
					(size 1.016 1.016)
					(thickness 0.1524)
				)
			)
		)
		(duplicate_pad_numbers_are_jumpers no)
		(fp_line
			(start 0.508 -0.9398)
			(end -0.508 -0.9398)
			(stroke
				(width 0.1524)
				(type default)
			)
			(layer "F.SilkS")
		)
		(fp_line
			(start -0.508 -0.9398)
			(end -0.508 0.9398)
			(stroke
				(width 0.1524)
				(type default)
			)
			(layer "F.SilkS")
		)
		(fp_rect
			(start -0.508 0.9398)
			(end 0.508 -0.9398)
			(stroke
				(width 0)
				(type default)
			)
			(fill no)
			(layer "F.CrtYd")
		)
		(fp_rect
			(start -0.508 0.9398)
			(end 0.508 -0.9398)
			(stroke
				(width 0)
				(type default)
			)
			(fill no)
			(layer "F.Fab")
		)
		(pad "1" smd custom
			(at 0 -0.4445 90)
			(size 0.1397 0.1397)
			(layers "F.Cu" "F.Mask" "F.Paste")
			(net "I2C_D_SDA_DAMP_B")
			(options
				(clearance outline)
				(anchor circle)
			)
			(primitives
				(gr_poly
					(pts
						(arc
							(start -0.1778 -0.2794)
							(mid -0.249642 -0.249642)
							(end -0.2794 -0.1778)
						)
						(arc
							(start -0.2794 0.1778)
							(mid -0.249642 0.249642)
							(end -0.1778 0.2794)
						)
						(arc
							(start 0.1778 0.2794)
							(mid 0.249642 0.249642)
							(end 0.2794 0.1778)
						)
						(arc
							(start 0.2794 -0.1778)
							(mid 0.249642 -0.249642)
							(end 0.1778 -0.2794)
						)
					)
					(width 0)
					(fill yes)
				)
			)
		)
		(pad "2" smd custom
			(at 0 0.4445 90)
			(size 0.1397 0.1397)
			(layers "F.Cu" "F.Mask" "F.Paste")
			(net "I2C_D_SDA")
			(options
				(clearance outline)
				(anchor circle)
			)
			(primitives
				(gr_poly
					(pts
						(arc
							(start -0.1778 -0.2794)
							(mid -0.249642 -0.249642)
							(end -0.2794 -0.1778)
						)
						(arc
							(start -0.2794 0.1778)
							(mid -0.249642 0.249642)
							(end -0.1778 0.2794)
						)
						(arc
							(start 0.1778 0.2794)
							(mid 0.249642 0.249642)
							(end 0.2794 0.1778)
						)
						(arc
							(start 0.2794 -0.1778)
							(mid 0.249642 -0.249642)
							(end 0.1778 -0.2794)
						)
					)
					(width 0)
					(fill yes)
				)
			)
		)
	)
)
